FILE_TYPE = CONNECTIVITY;
{Allegro Design Entry HDL 16.6-p007 (v16-6-112F) 10/10/2012}
"PAGE_NUMBER" = 14;
0"NC";
END.
